(kicad_pcb
	(version 20260206)
	(generator "pcbnew")
	(generator_version "10.0")
	(general
		(thickness 1.6)
		(legacy_teardrops no)
	)
	(paper "A4")
	(title_block
		(title "12092022_DA0F0TMDCD0_F0T_Management_Board_D_brd_V3_OCP.brd")
		(comment 1 "Grand Teton / footprints 208-212 of 1440")
	)
	(layers
		(0 "F.Cu" signal "TOP")
		(4 "In1.Cu" signal "GND")
		(6 "In2.Cu" signal "IN1")
		(8 "In3.Cu" signal "GND1")
		(10 "In4.Cu" signal "IN2")
		(12 "In5.Cu" signal "VCC")
		(14 "In6.Cu" signal "VCC1")
		(16 "In7.Cu" signal "IN3")
		(18 "In8.Cu" signal "GND2")
		(20 "In9.Cu" signal "IN4")
		(22 "In10.Cu" signal "GND3")
		(2 "B.Cu" signal "BOTTOM")
		(9 "F.Adhes" user "F.Adhesive")
		(11 "B.Adhes" user "B.Adhesive")
		(13 "F.Paste" user "Package Geometry/Pastemask Top")
		(15 "B.Paste" user "Package Geometry/Pastemask Bottom")
		(5 "F.SilkS" user "Ref Des/Silkscreen Top")
		(7 "B.SilkS" user "Ref Des/Silkscreen Bottom")
		(1 "F.Mask" user "Board Geometry/Soldermask Top")
		(3 "B.Mask" user "Board Geometry/Soldermask Bottom")
		(17 "Dwgs.User" user "User.Drawings")
		(19 "Cmts.User" user "User.Comments")
		(21 "Eco1.User" user "User.Eco1")
		(23 "Eco2.User" user "User.Eco2")
		(25 "Edge.Cuts" user "Board Geometry/Outline")
		(27 "Margin" user)
		(31 "F.CrtYd" user "Package Geometry/Place Bound Top")
		(29 "B.CrtYd" user "Package Geometry/Place Bound Bottom")
		(35 "F.Fab" user "Ref Des/Assembly Top")
		(33 "B.Fab" user "Ref Des/Assembly Bottom")
	)
	(footprint ""
		(layer "F.Cu")
		(at 85.29955 -44.427394 180)
		(property "Reference" "R333"
			(at 0 0 180)
			(layer "F.SilkS")
			(hide yes)
			(effects
				(font
					(size 1.27 1.27)
				)
			)
		)
		(property "Value" ""
			(at 0 0 180)
			(layer "F.Fab")
			(effects
				(font
					(size 1.27 1.27)
				)
			)
		)
		(duplicate_pad_numbers_are_jumpers no)
		(fp_line
			(start 0.7874 0.4064)
			(end -0.7874 0.4064)
			(stroke
				(width 0.1524)
				(type default)
			)
			(layer "F.SilkS")
		)
		(fp_line
			(start 0.7874 -0.4064)
			(end 0.7874 0.4064)
			(stroke
				(width 0.1524)
				(type default)
			)
			(layer "F.SilkS")
		)
		(fp_line
			(start -0.7874 0.4064)
			(end -0.7874 -0.4064)
			(stroke
				(width 0.1524)
				(type default)
			)
			(layer "F.SilkS")
		)
		(fp_line
			(start -0.7874 -0.4064)
			(end 0.7874 -0.4064)
			(stroke
				(width 0.1524)
				(type default)
			)
			(layer "F.SilkS")
		)
		(fp_line
			(start 0.67945 0.3048)
			(end 0.120396 0.3048)
			(stroke
				(width 0.1)
				(type default)
			)
			(layer "F.Fab")
		)
		(fp_line
			(start 0.67945 -0.3048)
			(end 0.67945 0.3048)
			(stroke
				(width 0.1)
				(type default)
			)
			(layer "F.Fab")
		)
		(fp_line
			(start 0.12065 -0.2794)
			(end 0.12065 -0.3048)
			(stroke
				(width 0.1)
				(type default)
			)
			(layer "F.Fab")
		)
		(fp_line
			(start 0.12065 -0.3048)
			(end 0.67945 -0.3048)
			(stroke
				(width 0.1)
				(type default)
			)
			(layer "F.Fab")
		)
		(fp_line
			(start 0.120396 0.3048)
			(end 0.120396 0.2794)
			(stroke
				(width 0.1)
				(type default)
			)
			(layer "F.Fab")
		)
		(fp_line
			(start 0.120396 0.2794)
			(end -0.12065 0.2794)
			(stroke
				(width 0.1)
				(type default)
			)
			(layer "F.Fab")
		)
		(fp_line
			(start -0.12065 0.3048)
			(end -0.67945 0.3048)
			(stroke
				(width 0.1)
				(type default)
			)
			(layer "F.Fab")
		)
		(fp_line
			(start -0.12065 0.2794)
			(end -0.12065 0.3048)
			(stroke
				(width 0.1)
				(type default)
			)
			(layer "F.Fab")
		)
		(fp_line
			(start -0.12065 -0.2794)
			(end 0.12065 -0.2794)
			(stroke
				(width 0.1)
				(type default)
			)
			(layer "F.Fab")
		)
		(fp_line
			(start -0.12065 -0.305054)
			(end -0.12065 -0.2794)
			(stroke
				(width 0.1)
				(type default)
			)
			(layer "F.Fab")
		)
		(fp_line
			(start -0.67945 0.3048)
			(end -0.67945 -0.305054)
			(stroke
				(width 0.1)
				(type default)
			)
			(layer "F.Fab")
		)
		(fp_line
			(start -0.67945 -0.305054)
			(end -0.12065 -0.305054)
			(stroke
				(width 0.1)
				(type default)
			)
			(layer "F.Fab")
		)
		(pad "1" smd circle
			(at -0.40005 0 180)
			(size 0 0)
			(layers "F.Cu" "F.Mask" "F.Paste")
			(net "GND")
		)
		(pad "2" smd circle
			(at 0.40005 0 180)
			(size 0 0)
			(layers "F.Cu" "F.Mask" "F.Paste")
			(net "M_BMC_DDR4_MA<7>")
		)
	)
	(footprint ""
		(layer "F.Cu")
		(at 57.18556 -94.5896)
		(property "Reference" "R464"
			(at 0 0 0)
			(layer "F.SilkS")
			(hide yes)
			(effects
				(font
					(size 1.27 1.27)
				)
			)
		)
		(property "Value" ""
			(at 0 0 0)
			(layer "F.Fab")
			(effects
				(font
					(size 1.27 1.27)
				)
			)
		)
		(duplicate_pad_numbers_are_jumpers no)
		(fp_line
			(start -0.7874 -0.4064)
			(end 0.7874 -0.4064)
			(stroke
				(width 0.1524)
				(type default)
			)
			(layer "F.SilkS")
		)
		(fp_line
			(start -0.7874 0.4064)
			(end -0.7874 -0.4064)
			(stroke
				(width 0.1524)
				(type default)
			)
			(layer "F.SilkS")
		)
		(fp_line
			(start 0.7874 -0.4064)
			(end 0.7874 0.4064)
			(stroke
				(width 0.1524)
				(type default)
			)
			(layer "F.SilkS")
		)
		(fp_line
			(start 0.7874 0.4064)
			(end -0.7874 0.4064)
			(stroke
				(width 0.1524)
				(type default)
			)
			(layer "F.SilkS")
		)
		(fp_line
			(start -0.67945 -0.305054)
			(end -0.12065 -0.305054)
			(stroke
				(width 0.1)
				(type default)
			)
			(layer "F.Fab")
		)
		(fp_line
			(start -0.67945 0.3048)
			(end -0.67945 -0.305054)
			(stroke
				(width 0.1)
				(type default)
			)
			(layer "F.Fab")
		)
		(fp_line
			(start -0.12065 -0.305054)
			(end -0.12065 -0.2794)
			(stroke
				(width 0.1)
				(type default)
			)
			(layer "F.Fab")
		)
		(fp_line
			(start -0.12065 -0.2794)
			(end 0.12065 -0.2794)
			(stroke
				(width 0.1)
				(type default)
			)
			(layer "F.Fab")
		)
		(fp_line
			(start -0.12065 0.2794)
			(end -0.12065 0.3048)
			(stroke
				(width 0.1)
				(type default)
			)
			(layer "F.Fab")
		)
		(fp_line
			(start -0.12065 0.3048)
			(end -0.67945 0.3048)
			(stroke
				(width 0.1)
				(type default)
			)
			(layer "F.Fab")
		)
		(fp_line
			(start 0.120396 0.2794)
			(end -0.12065 0.2794)
			(stroke
				(width 0.1)
				(type default)
			)
			(layer "F.Fab")
		)
		(fp_line
			(start 0.120396 0.3048)
			(end 0.120396 0.2794)
			(stroke
				(width 0.1)
				(type default)
			)
			(layer "F.Fab")
		)
		(fp_line
			(start 0.12065 -0.3048)
			(end 0.67945 -0.3048)
			(stroke
				(width 0.1)
				(type default)
			)
			(layer "F.Fab")
		)
		(fp_line
			(start 0.12065 -0.2794)
			(end 0.12065 -0.3048)
			(stroke
				(width 0.1)
				(type default)
			)
			(layer "F.Fab")
		)
		(fp_line
			(start 0.67945 -0.3048)
			(end 0.67945 0.3048)
			(stroke
				(width 0.1)
				(type default)
			)
			(layer "F.Fab")
		)
		(fp_line
			(start 0.67945 0.3048)
			(end 0.120396 0.3048)
			(stroke
				(width 0.1)
				(type default)
			)
			(layer "F.Fab")
		)
		(pad "1" smd circle
			(at -0.40005 0)
			(size 0 0)
			(layers "F.Cu" "F.Mask" "F.Paste")
			(net "P3V3_AUX")
		)
		(pad "2" smd circle
			(at 0.40005 0)
			(size 0 0)
			(layers "F.Cu" "F.Mask" "F.Paste")
			(net "FM_TPM_PRSNT_0_N")
		)
	)
	(footprint ""
		(layer "F.Cu")
		(at 16.690086 -10.729976 90)
		(property "Reference" "J14"
			(at 0.573024 -3.328416 90)
			(unlocked yes)
			(layer "F.SilkS")
			(effects
				(font
					(size 0.7874 0.5842)
					(thickness 0.1524)
				)
				(justify left)
			)
		)
		(property "Value" ""
			(at 0 0 90)
			(layer "F.Fab")
			(effects
				(font
					(size 1.27 1.27)
				)
			)
		)
		(duplicate_pad_numbers_are_jumpers no)
		(fp_line
			(start 3.81 -1.459992)
			(end 3.81 9.079992)
			(stroke
				(width 0.1524)
				(type default)
			)
			(layer "F.SilkS")
		)
		(fp_line
			(start -1.27 -1.459992)
			(end 3.81 -1.459992)
			(stroke
				(width 0.1524)
				(type default)
			)
			(layer "F.SilkS")
		)
		(fp_line
			(start 3.81 9.079992)
			(end -1.27 9.079992)
			(stroke
				(width 0.1524)
				(type default)
			)
			(layer "F.SilkS")
		)
		(fp_line
			(start -1.27 9.079992)
			(end -1.27 -1.459992)
			(stroke
				(width 0.1524)
				(type default)
			)
			(layer "F.SilkS")
		)
		(fp_poly
			(pts
				(xy -2.54 0.508) (xy -2.54 -0.508) (xy -1.524 0)
			)
			(stroke
				(width 0)
				(type default)
			)
			(fill yes)
			(layer "F.SilkS")
		)
		(fp_line
			(start 3.81 -1.459992)
			(end 3.81 9.079992)
			(stroke
				(width 0.1)
				(type default)
			)
			(layer "F.Fab")
		)
		(fp_line
			(start -1.27 -1.459992)
			(end 3.81 -1.459992)
			(stroke
				(width 0.1)
				(type default)
			)
			(layer "F.Fab")
		)
		(fp_line
			(start 3.81 9.079992)
			(end -1.27 9.079992)
			(stroke
				(width 0.1)
				(type default)
			)
			(layer "F.Fab")
		)
		(fp_line
			(start -1.27 9.079992)
			(end -1.27 -1.459992)
			(stroke
				(width 0.1)
				(type default)
			)
			(layer "F.Fab")
		)
		(fp_poly
			(pts
				(xy -2.54 0.508) (xy -2.54 -0.508) (xy -1.524 0)
			)
			(stroke
				(width 0)
				(type default)
			)
			(fill yes)
			(layer "F.Fab")
		)
		(fp_text user "2"
			(at 2.629154 -2.288286 0)
			(unlocked yes)
			(layer "F.SilkS")
			(effects
				(font
					(size 0.7874 0.5842)
					(thickness 0.1524)
				)
			)
		)
		(fp_text user "8"
			(at 4.48183 7.6073 0)
			(unlocked yes)
			(layer "F.SilkS")
			(effects
				(font
					(size 0.7874 0.5842)
					(thickness 0.1524)
				)
			)
		)
		(fp_text user "7"
			(at -1.908556 8.800592 0)
			(unlocked yes)
			(layer "F.SilkS")
			(effects
				(font
					(size 0.7874 0.5842)
					(thickness 0.1524)
				)
			)
		)
		(fp_text user "2"
			(at 2.56413 -1.1811 0)
			(unlocked yes)
			(layer "B.SilkS")
			(effects
				(font
					(size 0.7874 0.5842)
					(thickness 0.1524)
				)
				(justify mirror)
			)
		)
		(fp_text user "1"
			(at -0.05207 -1.1303 0)
			(unlocked yes)
			(layer "B.SilkS")
			(effects
				(font
					(size 0.7874 0.5842)
					(thickness 0.1524)
				)
				(justify mirror)
			)
		)
		(fp_text user "7"
			(at -0.01397 8.7249 0)
			(unlocked yes)
			(layer "B.SilkS")
			(effects
				(font
					(size 0.7874 0.5842)
					(thickness 0.1524)
				)
				(justify mirror)
			)
		)
		(fp_text user "8"
			(at 2.56413 8.7757 0)
			(unlocked yes)
			(layer "B.SilkS")
			(effects
				(font
					(size 0.7874 0.5842)
					(thickness 0.1524)
				)
				(justify mirror)
			)
		)
		(fp_text user "2"
			(at 2.56413 -1.1811 0)
			(unlocked yes)
			(layer "B.Fab")
			(effects
				(font
					(size 0.7874 0.5842)
					(thickness 0.1524)
				)
				(justify mirror)
			)
		)
		(fp_text user "1"
			(at -0.05207 -1.1303 0)
			(unlocked yes)
			(layer "B.Fab")
			(effects
				(font
					(size 0.7874 0.5842)
					(thickness 0.1524)
				)
				(justify mirror)
			)
		)
		(fp_text user "7"
			(at -0.01397 8.7249 0)
			(unlocked yes)
			(layer "B.Fab")
			(effects
				(font
					(size 0.7874 0.5842)
					(thickness 0.1524)
				)
				(justify mirror)
			)
		)
		(fp_text user "8"
			(at 2.56413 8.7757 0)
			(unlocked yes)
			(layer "B.Fab")
			(effects
				(font
					(size 0.7874 0.5842)
					(thickness 0.1524)
				)
				(justify mirror)
			)
		)
		(fp_text user "2"
			(at 4.48183 0 0)
			(unlocked yes)
			(layer "F.Fab")
			(effects
				(font
					(size 0.7874 0.5842)
					(thickness 0.1524)
				)
			)
		)
		(fp_text user "7"
			(at -2.07137 7.5565 0)
			(unlocked yes)
			(layer "F.Fab")
			(effects
				(font
					(size 0.7874 0.5842)
					(thickness 0.1524)
				)
			)
		)
		(fp_text user "8"
			(at 4.48183 7.6073 0)
			(unlocked yes)
			(layer "F.Fab")
			(effects
				(font
					(size 0.7874 0.5842)
					(thickness 0.1524)
				)
			)
		)
		(pad "1" thru_hole rect
			(at 0 0)
			(size 1.5494 1.5494)
			(drill 1.0414)
			(layers "*.Cu" "*.Mask")
			(remove_unused_layers no)
			(net "P3V3_AUX")
			(clearance 0)
			(padstack
				(mode front_inner_back)
				(layer "Inner"
					(shape circle)
					(size 1.5494 1.5494)
					(clearance 0)
				)
				(layer "B.Cu"
					(shape rect)
					(size 1.5494 1.5494)
					(clearance 0)
				)
			)
		)
		(pad "2" thru_hole circle
			(at 2.54 0)
			(size 1.5494 1.5494)
			(drill 1.0414)
			(layers "*.Cu" "*.Mask")
			(remove_unused_layers no)
			(net "SMB_TMP421_BMC_MM2_SDA")
			(clearance 0)
		)
		(pad "3" thru_hole circle
			(at 0 2.54)
			(size 1.5494 1.5494)
			(drill 1.0414)
			(layers "*.Cu" "*.Mask")
			(remove_unused_layers no)
			(net "TMC75_A0")
			(clearance 0)
		)
		(pad "4" thru_hole circle
			(at 2.54 2.54)
			(size 1.5494 1.5494)
			(drill 1.0414)
			(layers "*.Cu" "*.Mask")
			(remove_unused_layers no)
			(net "SMB_TMP421_BMC_MM2_SCL")
			(clearance 0)
		)
		(pad "5" thru_hole circle
			(at 0 5.08)
			(size 1.5494 1.5494)
			(drill 1.0414)
			(layers "*.Cu" "*.Mask")
			(remove_unused_layers no)
			(net "TMC75_A1")
			(clearance 0)
		)
		(pad "6" thru_hole circle
			(at 2.54 5.08)
			(size 1.5494 1.5494)
			(drill 1.0414)
			(layers "*.Cu" "*.Mask")
			(remove_unused_layers no)
			(net "SMB_BMC_ALERT16_R_N")
			(clearance 0)
		)
		(pad "7" thru_hole circle
			(at 0 7.62)
			(size 1.5494 1.5494)
			(drill 1.0414)
			(layers "*.Cu" "*.Mask")
			(remove_unused_layers no)
			(net "TMC75_A2")
			(clearance 0)
		)
		(pad "8" thru_hole circle
			(at 2.54 7.62)
			(size 1.5494 1.5494)
			(drill 1.0414)
			(layers "*.Cu" "*.Mask")
			(remove_unused_layers no)
			(net "GND")
			(clearance 0)
		)
	)
	(footprint ""
		(layer "F.Cu")
		(at 78.994 -82.55 -90)
		(property "Reference" "C226"
			(at 0 0 270)
			(layer "F.SilkS")
			(hide yes)
			(effects
				(font
					(size 1.27 1.27)
				)
			)
		)
		(property "Value" ""
			(at 0 0 270)
			(layer "F.Fab")
			(effects
				(font
					(size 1.27 1.27)
				)
			)
		)
		(duplicate_pad_numbers_are_jumpers no)
		(fp_line
			(start -0.7874 0.4064)
			(end -0.7874 -0.4064)
			(stroke
				(width 0.1524)
				(type default)
			)
			(layer "F.SilkS")
		)
		(fp_line
			(start 0.7874 0.4064)
			(end -0.7874 0.4064)
			(stroke
				(width 0.1524)
				(type default)
			)
			(layer "F.SilkS")
		)
		(fp_line
			(start -0.7874 -0.4064)
			(end 0.7874 -0.4064)
			(stroke
				(width 0.1524)
				(type default)
			)
			(layer "F.SilkS")
		)
		(fp_line
			(start 0.7874 -0.4064)
			(end 0.7874 0.4064)
			(stroke
				(width 0.1524)
				(type default)
			)
			(layer "F.SilkS")
		)
		(fp_line
			(start -0.67945 0.3048)
			(end -0.67945 -0.305054)
			(stroke
				(width 0.1)
				(type default)
			)
			(layer "F.Fab")
		)
		(fp_line
			(start -0.12065 0.3048)
			(end -0.67945 0.3048)
			(stroke
				(width 0.1)
				(type default)
			)
			(layer "F.Fab")
		)
		(fp_line
			(start 0.120396 0.3048)
			(end 0.120396 0.2794)
			(stroke
				(width 0.1)
				(type default)
			)
			(layer "F.Fab")
		)
		(fp_line
			(start 0.67945 0.3048)
			(end 0.120396 0.3048)
			(stroke
				(width 0.1)
				(type default)
			)
			(layer "F.Fab")
		)
		(fp_line
			(start -0.12065 0.2794)
			(end -0.12065 0.3048)
			(stroke
				(width 0.1)
				(type default)
			)
			(layer "F.Fab")
		)
		(fp_line
			(start 0.120396 0.2794)
			(end -0.12065 0.2794)
			(stroke
				(width 0.1)
				(type default)
			)
			(layer "F.Fab")
		)
		(fp_line
			(start -0.12065 -0.2794)
			(end 0.12065 -0.2794)
			(stroke
				(width 0.1)
				(type default)
			)
			(layer "F.Fab")
		)
		(fp_line
			(start 0.12065 -0.2794)
			(end 0.12065 -0.3048)
			(stroke
				(width 0.1)
				(type default)
			)
			(layer "F.Fab")
		)
		(fp_line
			(start 0.12065 -0.3048)
			(end 0.67945 -0.3048)
			(stroke
				(width 0.1)
				(type default)
			)
			(layer "F.Fab")
		)
		(fp_line
			(start 0.67945 -0.3048)
			(end 0.67945 0.3048)
			(stroke
				(width 0.1)
				(type default)
			)
			(layer "F.Fab")
		)
		(fp_line
			(start -0.67945 -0.305054)
			(end -0.12065 -0.305054)
			(stroke
				(width 0.1)
				(type default)
			)
			(layer "F.Fab")
		)
		(fp_line
			(start -0.12065 -0.305054)
			(end -0.12065 -0.2794)
			(stroke
				(width 0.1)
				(type default)
			)
			(layer "F.Fab")
		)
		(pad "1" smd circle
			(at -0.40005 0 270)
			(size 0 0)
			(layers "F.Cu" "F.Mask" "F.Paste")
			(net "P12V_AUX")
		)
		(pad "2" smd circle
			(at 0.40005 0 270)
			(size 0 0)
			(layers "F.Cu" "F.Mask" "F.Paste")
			(net "GND")
		)
	)
	(footprint ""
		(layer "F.Cu")
		(at 56.79948 -65.76822 180)
		(property "Reference" "R465"
			(at 0 0 180)
			(layer "F.SilkS")
			(hide yes)
			(effects
				(font
					(size 1.27 1.27)
				)
			)
		)
		(property "Value" ""
			(at 0 0 180)
			(layer "F.Fab")
			(effects
				(font
					(size 1.27 1.27)
				)
			)
		)
		(duplicate_pad_numbers_are_jumpers no)
		(fp_line
			(start 0.7874 0.4064)
			(end -0.7874 0.4064)
			(stroke
				(width 0.1524)
				(type default)
			)
			(layer "F.SilkS")
		)
		(fp_line
			(start 0.7874 -0.4064)
			(end 0.7874 0.4064)
			(stroke
				(width 0.1524)
				(type default)
			)
			(layer "F.SilkS")
		)
		(fp_line
			(start -0.7874 0.4064)
			(end -0.7874 -0.4064)
			(stroke
				(width 0.1524)
				(type default)
			)
			(layer "F.SilkS")
		)
		(fp_line
			(start -0.7874 -0.4064)
			(end 0.7874 -0.4064)
			(stroke
				(width 0.1524)
				(type default)
			)
			(layer "F.SilkS")
		)
		(fp_line
			(start 0.67945 0.3048)
			(end 0.120396 0.3048)
			(stroke
				(width 0.1)
				(type default)
			)
			(layer "F.Fab")
		)
		(fp_line
			(start 0.67945 -0.3048)
			(end 0.67945 0.3048)
			(stroke
				(width 0.1)
				(type default)
			)
			(layer "F.Fab")
		)
		(fp_line
			(start 0.12065 -0.2794)
			(end 0.12065 -0.3048)
			(stroke
				(width 0.1)
				(type default)
			)
			(layer "F.Fab")
		)
		(fp_line
			(start 0.12065 -0.3048)
			(end 0.67945 -0.3048)
			(stroke
				(width 0.1)
				(type default)
			)
			(layer "F.Fab")
		)
		(fp_line
			(start 0.120396 0.3048)
			(end 0.120396 0.2794)
			(stroke
				(width 0.1)
				(type default)
			)
			(layer "F.Fab")
		)
		(fp_line
			(start 0.120396 0.2794)
			(end -0.12065 0.2794)
			(stroke
				(width 0.1)
				(type default)
			)
			(layer "F.Fab")
		)
		(fp_line
			(start -0.12065 0.3048)
			(end -0.67945 0.3048)
			(stroke
				(width 0.1)
				(type default)
			)
			(layer "F.Fab")
		)
		(fp_line
			(start -0.12065 0.2794)
			(end -0.12065 0.3048)
			(stroke
				(width 0.1)
				(type default)
			)
			(layer "F.Fab")
		)
		(fp_line
			(start -0.12065 -0.2794)
			(end 0.12065 -0.2794)
			(stroke
				(width 0.1)
				(type default)
			)
			(layer "F.Fab")
		)
		(fp_line
			(start -0.12065 -0.305054)
			(end -0.12065 -0.2794)
			(stroke
				(width 0.1)
				(type default)
			)
			(layer "F.Fab")
		)
		(fp_line
			(start -0.67945 0.3048)
			(end -0.67945 -0.305054)
			(stroke
				(width 0.1)
				(type default)
			)
			(layer "F.Fab")
		)
		(fp_line
			(start -0.67945 -0.305054)
			(end -0.12065 -0.305054)
			(stroke
				(width 0.1)
				(type default)
			)
			(layer "F.Fab")
		)
		(pad "1" smd circle
			(at -0.40005 0 180)
			(size 0 0)
			(layers "F.Cu" "F.Mask" "F.Paste")
			(net "FM_FLASH_LATCH_N_R1")
		)
		(pad "2" smd circle
			(at 0.40005 0 180)
			(size 0 0)
			(layers "F.Cu" "F.Mask" "F.Paste")
			(net "FM_FLASH_LATCH_N")
		)
	)
)
